(kicad_pcb
	(version 20260206)
	(generator "pcbnew")
	(generator_version "10.0")
	(general
		(thickness 1.6)
		(legacy_teardrops no)
	)
	(paper "A4")
	(title_block
		(title "04192023_DAF0TMB3IC0_F0TG_MB_C_brd_V02_OCP.brd")
		(comment 1 "Grand Teton / footprints 4227-4233 of 8354")
	)
	(layers
		(0 "F.Cu" signal "TOP")
		(4 "In1.Cu" signal "GND")
		(6 "In2.Cu" signal "IN1")
		(8 "In3.Cu" signal "GND1")
		(10 "In4.Cu" signal "IN2")
		(12 "In5.Cu" signal "GND2")
		(14 "In6.Cu" signal "IN3")
		(16 "In7.Cu" signal "GND3")
		(18 "In8.Cu" signal "VCC")
		(20 "In9.Cu" signal "VCC1")
		(22 "In10.Cu" signal "GND4")
		(24 "In11.Cu" signal "IN4")
		(26 "In12.Cu" signal "GND5")
		(28 "In13.Cu" signal "IN5")
		(30 "In14.Cu" signal "GND6")
		(32 "In15.Cu" signal "IN6")
		(34 "In16.Cu" signal "GND7")
		(2 "B.Cu" signal "BOTTOM")
		(9 "F.Adhes" user "F.Adhesive")
		(11 "B.Adhes" user "B.Adhesive")
		(13 "F.Paste" user "Package Geometry/Pastemask Top")
		(15 "B.Paste" user "Package Geometry/Pastemask Bottom")
		(5 "F.SilkS" user "Ref Des/Silkscreen Top")
		(7 "B.SilkS" user "Ref Des/Silkscreen Bottom")
		(1 "F.Mask" user "Board Geometry/Soldermask Top")
		(3 "B.Mask" user "Board Geometry/Soldermask Bottom")
		(17 "Dwgs.User" user "User.Drawings")
		(19 "Cmts.User" user "User.Comments")
		(21 "Eco1.User" user "User.Eco1")
		(23 "Eco2.User" user "User.Eco2")
		(25 "Edge.Cuts" user "Board Geometry/Outline")
		(27 "Margin" user)
		(31 "F.CrtYd" user "Package Geometry/Place Bound Top")
		(29 "B.CrtYd" user "Package Geometry/Place Bound Bottom")
		(35 "F.Fab" user "Ref Des/Assembly Top")
		(33 "B.Fab" user "Ref Des/Assembly Bottom")
	)
	(footprint ""
		(layer "F.Cu")
		(at 99.822 -79.121)
		(property "Reference" "C1061"
			(at 0 0 0)
			(layer "F.SilkS")
			(hide yes)
			(effects
				(font
					(size 1.27 1.27)
				)
			)
		)
		(property "Value" ""
			(at 0 0 0)
			(layer "F.Fab")
			(effects
				(font
					(size 1.27 1.27)
				)
			)
		)
		(duplicate_pad_numbers_are_jumpers no)
		(fp_line
			(start -0.7874 -0.4064)
			(end 0.7874 -0.4064)
			(stroke
				(width 0.1524)
				(type default)
			)
			(layer "F.SilkS")
		)
		(fp_line
			(start -0.7874 0.4064)
			(end -0.7874 -0.4064)
			(stroke
				(width 0.1524)
				(type default)
			)
			(layer "F.SilkS")
		)
		(fp_line
			(start 0.7874 -0.4064)
			(end 0.7874 0.4064)
			(stroke
				(width 0.1524)
				(type default)
			)
			(layer "F.SilkS")
		)
		(fp_line
			(start 0.7874 0.4064)
			(end -0.7874 0.4064)
			(stroke
				(width 0.1524)
				(type default)
			)
			(layer "F.SilkS")
		)
		(fp_line
			(start -0.67945 -0.305054)
			(end -0.12065 -0.305054)
			(stroke
				(width 0.1)
				(type default)
			)
			(layer "F.Fab")
		)
		(fp_line
			(start -0.67945 0.3048)
			(end -0.67945 -0.305054)
			(stroke
				(width 0.1)
				(type default)
			)
			(layer "F.Fab")
		)
		(fp_line
			(start -0.12065 -0.305054)
			(end -0.12065 -0.2794)
			(stroke
				(width 0.1)
				(type default)
			)
			(layer "F.Fab")
		)
		(fp_line
			(start -0.12065 -0.2794)
			(end 0.12065 -0.2794)
			(stroke
				(width 0.1)
				(type default)
			)
			(layer "F.Fab")
		)
		(fp_line
			(start -0.12065 0.2794)
			(end -0.12065 0.3048)
			(stroke
				(width 0.1)
				(type default)
			)
			(layer "F.Fab")
		)
		(fp_line
			(start -0.12065 0.3048)
			(end -0.67945 0.3048)
			(stroke
				(width 0.1)
				(type default)
			)
			(layer "F.Fab")
		)
		(fp_line
			(start 0.120396 0.2794)
			(end -0.12065 0.2794)
			(stroke
				(width 0.1)
				(type default)
			)
			(layer "F.Fab")
		)
		(fp_line
			(start 0.120396 0.3048)
			(end 0.120396 0.2794)
			(stroke
				(width 0.1)
				(type default)
			)
			(layer "F.Fab")
		)
		(fp_line
			(start 0.12065 -0.3048)
			(end 0.67945 -0.3048)
			(stroke
				(width 0.1)
				(type default)
			)
			(layer "F.Fab")
		)
		(fp_line
			(start 0.12065 -0.2794)
			(end 0.12065 -0.3048)
			(stroke
				(width 0.1)
				(type default)
			)
			(layer "F.Fab")
		)
		(fp_line
			(start 0.67945 -0.3048)
			(end 0.67945 0.3048)
			(stroke
				(width 0.1)
				(type default)
			)
			(layer "F.Fab")
		)
		(fp_line
			(start 0.67945 0.3048)
			(end 0.120396 0.3048)
			(stroke
				(width 0.1)
				(type default)
			)
			(layer "F.Fab")
		)
		(pad "1" smd circle
			(at -0.40005 0)
			(size 0 0)
			(layers "F.Cu" "F.Mask" "F.Paste")
			(net "P3V3_AUX")
		)
		(pad "2" smd circle
			(at 0.40005 0)
			(size 0 0)
			(layers "F.Cu" "F.Mask" "F.Paste")
			(net "GND")
		)
	)
	(footprint ""
		(layer "F.Cu")
		(at 41.5544 -389.8392 180)
		(property "Reference" "R6709"
			(at 0 0 180)
			(layer "F.SilkS")
			(hide yes)
			(effects
				(font
					(size 1.27 1.27)
				)
			)
		)
		(property "Value" ""
			(at 0 0 180)
			(layer "F.Fab")
			(effects
				(font
					(size 1.27 1.27)
				)
			)
		)
		(duplicate_pad_numbers_are_jumpers no)
		(fp_line
			(start 0.32512 0.175006)
			(end -0.32512 0.175006)
			(stroke
				(width 0.1)
				(type default)
			)
			(layer "F.Fab")
		)
		(fp_line
			(start 0.32512 -0.175006)
			(end 0.32512 0.175006)
			(stroke
				(width 0.1)
				(type default)
			)
			(layer "F.Fab")
		)
		(fp_line
			(start -0.32512 0.175006)
			(end -0.32512 -0.175006)
			(stroke
				(width 0.1)
				(type default)
			)
			(layer "F.Fab")
		)
		(fp_line
			(start -0.32512 -0.175006)
			(end 0.32512 -0.175006)
			(stroke
				(width 0.1)
				(type default)
			)
			(layer "F.Fab")
		)
		(pad "1" smd rect
			(at -0.2667 0 180)
			(size 0.3048 0.381)
			(layers "F.Cu" "F.Mask" "F.Paste")
			(net "RST_RT_CPU1_P0_RESET_N")
		)
		(pad "2" smd rect
			(at 0.2667 0)
			(size 0.3048 0.381)
			(layers "F.Cu" "F.Mask" "F.Paste")
			(net "RST_RT_CPU1_P0_RESET_R_N")
		)
	)
	(footprint ""
		(layer "F.Cu")
		(at 449.561712 -423.413936)
		(property "Reference" "PC6607"
			(at 0 0 0)
			(layer "F.SilkS")
			(hide yes)
			(effects
				(font
					(size 1.27 1.27)
				)
			)
		)
		(property "Value" ""
			(at 0 0 0)
			(layer "F.Fab")
			(effects
				(font
					(size 1.27 1.27)
				)
			)
		)
		(duplicate_pad_numbers_are_jumpers no)
		(fp_line
			(start -0.7874 -0.4064)
			(end 0.7874 -0.4064)
			(stroke
				(width 0.1524)
				(type default)
			)
			(layer "F.SilkS")
		)
		(fp_line
			(start -0.7874 0.4064)
			(end -0.7874 -0.4064)
			(stroke
				(width 0.1524)
				(type default)
			)
			(layer "F.SilkS")
		)
		(fp_line
			(start 0.7874 -0.4064)
			(end 0.7874 0.4064)
			(stroke
				(width 0.1524)
				(type default)
			)
			(layer "F.SilkS")
		)
		(fp_line
			(start 0.7874 0.4064)
			(end -0.7874 0.4064)
			(stroke
				(width 0.1524)
				(type default)
			)
			(layer "F.SilkS")
		)
		(fp_line
			(start -0.67945 -0.305054)
			(end -0.12065 -0.305054)
			(stroke
				(width 0.1)
				(type default)
			)
			(layer "F.Fab")
		)
		(fp_line
			(start -0.67945 0.3048)
			(end -0.67945 -0.305054)
			(stroke
				(width 0.1)
				(type default)
			)
			(layer "F.Fab")
		)
		(fp_line
			(start -0.12065 -0.305054)
			(end -0.12065 -0.2794)
			(stroke
				(width 0.1)
				(type default)
			)
			(layer "F.Fab")
		)
		(fp_line
			(start -0.12065 -0.2794)
			(end 0.12065 -0.2794)
			(stroke
				(width 0.1)
				(type default)
			)
			(layer "F.Fab")
		)
		(fp_line
			(start -0.12065 0.2794)
			(end -0.12065 0.3048)
			(stroke
				(width 0.1)
				(type default)
			)
			(layer "F.Fab")
		)
		(fp_line
			(start -0.12065 0.3048)
			(end -0.67945 0.3048)
			(stroke
				(width 0.1)
				(type default)
			)
			(layer "F.Fab")
		)
		(fp_line
			(start 0.120396 0.2794)
			(end -0.12065 0.2794)
			(stroke
				(width 0.1)
				(type default)
			)
			(layer "F.Fab")
		)
		(fp_line
			(start 0.120396 0.3048)
			(end 0.120396 0.2794)
			(stroke
				(width 0.1)
				(type default)
			)
			(layer "F.Fab")
		)
		(fp_line
			(start 0.12065 -0.3048)
			(end 0.67945 -0.3048)
			(stroke
				(width 0.1)
				(type default)
			)
			(layer "F.Fab")
		)
		(fp_line
			(start 0.12065 -0.2794)
			(end 0.12065 -0.3048)
			(stroke
				(width 0.1)
				(type default)
			)
			(layer "F.Fab")
		)
		(fp_line
			(start 0.67945 -0.3048)
			(end 0.67945 0.3048)
			(stroke
				(width 0.1)
				(type default)
			)
			(layer "F.Fab")
		)
		(fp_line
			(start 0.67945 0.3048)
			(end 0.120396 0.3048)
			(stroke
				(width 0.1)
				(type default)
			)
			(layer "F.Fab")
		)
		(pad "1" smd circle
			(at -0.40005 0)
			(size 0 0)
			(layers "F.Cu" "F.Mask" "F.Paste")
			(net "P0V9_RETIMER_CPU0_TEMP0")
		)
		(pad "2" smd circle
			(at 0.40005 0)
			(size 0 0)
			(layers "F.Cu" "F.Mask" "F.Paste")
			(net "GND")
		)
	)
	(footprint ""
		(layer "F.Cu")
		(at 94.36481 -182.677562 90)
		(property "Reference" "PC259_C0P1_2"
			(at 0 0 90)
			(layer "F.SilkS")
			(hide yes)
			(effects
				(font
					(size 1.27 1.27)
				)
			)
		)
		(property "Value" ""
			(at 0 0 90)
			(layer "F.Fab")
			(effects
				(font
					(size 1.27 1.27)
				)
			)
		)
		(duplicate_pad_numbers_are_jumpers no)
		(fp_line
			(start 0.7874 -0.4064)
			(end 0.7874 0.4064)
			(stroke
				(width 0.1524)
				(type default)
			)
			(layer "F.SilkS")
		)
		(fp_line
			(start -0.7874 -0.4064)
			(end 0.7874 -0.4064)
			(stroke
				(width 0.1524)
				(type default)
			)
			(layer "F.SilkS")
		)
		(fp_line
			(start 0.7874 0.4064)
			(end -0.7874 0.4064)
			(stroke
				(width 0.1524)
				(type default)
			)
			(layer "F.SilkS")
		)
		(fp_line
			(start -0.7874 0.4064)
			(end -0.7874 -0.4064)
			(stroke
				(width 0.1524)
				(type default)
			)
			(layer "F.SilkS")
		)
		(fp_line
			(start -0.12065 -0.305054)
			(end -0.12065 -0.2794)
			(stroke
				(width 0.1)
				(type default)
			)
			(layer "F.Fab")
		)
		(fp_line
			(start -0.67945 -0.305054)
			(end -0.12065 -0.305054)
			(stroke
				(width 0.1)
				(type default)
			)
			(layer "F.Fab")
		)
		(fp_line
			(start 0.67945 -0.3048)
			(end 0.67945 0.3048)
			(stroke
				(width 0.1)
				(type default)
			)
			(layer "F.Fab")
		)
		(fp_line
			(start 0.12065 -0.3048)
			(end 0.67945 -0.3048)
			(stroke
				(width 0.1)
				(type default)
			)
			(layer "F.Fab")
		)
		(fp_line
			(start 0.12065 -0.2794)
			(end 0.12065 -0.3048)
			(stroke
				(width 0.1)
				(type default)
			)
			(layer "F.Fab")
		)
		(fp_line
			(start -0.12065 -0.2794)
			(end 0.12065 -0.2794)
			(stroke
				(width 0.1)
				(type default)
			)
			(layer "F.Fab")
		)
		(fp_line
			(start 0.120396 0.2794)
			(end -0.12065 0.2794)
			(stroke
				(width 0.1)
				(type default)
			)
			(layer "F.Fab")
		)
		(fp_line
			(start -0.12065 0.2794)
			(end -0.12065 0.3048)
			(stroke
				(width 0.1)
				(type default)
			)
			(layer "F.Fab")
		)
		(fp_line
			(start 0.67945 0.3048)
			(end 0.120396 0.3048)
			(stroke
				(width 0.1)
				(type default)
			)
			(layer "F.Fab")
		)
		(fp_line
			(start 0.120396 0.3048)
			(end 0.120396 0.2794)
			(stroke
				(width 0.1)
				(type default)
			)
			(layer "F.Fab")
		)
		(fp_line
			(start -0.12065 0.3048)
			(end -0.67945 0.3048)
			(stroke
				(width 0.1)
				(type default)
			)
			(layer "F.Fab")
		)
		(fp_line
			(start -0.67945 0.3048)
			(end -0.67945 -0.305054)
			(stroke
				(width 0.1)
				(type default)
			)
			(layer "F.Fab")
		)
		(pad "1" smd circle
			(at -0.40005 0 90)
			(size 0 0)
			(layers "F.Cu" "F.Mask" "F.Paste")
			(net "PVDDCR_CPU0_P1_PVCC")
		)
		(pad "2" smd circle
			(at 0.40005 0 90)
			(size 0 0)
			(layers "F.Cu" "F.Mask" "F.Paste")
			(net "GND")
		)
	)
	(footprint ""
		(layer "F.Cu")
		(at 113.376964 -261.748016 -90)
		(property "Reference" "C2282"
			(at 0 0 270)
			(layer "F.SilkS")
			(hide yes)
			(effects
				(font
					(size 1.27 1.27)
				)
			)
		)
		(property "Value" ""
			(at 0 0 270)
			(layer "F.Fab")
			(effects
				(font
					(size 1.27 1.27)
				)
			)
		)
		(duplicate_pad_numbers_are_jumpers no)
		(fp_line
			(start -0.7874 0.4064)
			(end -0.7874 -0.4064)
			(stroke
				(width 0.1524)
				(type default)
			)
			(layer "F.SilkS")
		)
		(fp_line
			(start 0.7874 0.4064)
			(end -0.7874 0.4064)
			(stroke
				(width 0.1524)
				(type default)
			)
			(layer "F.SilkS")
		)
		(fp_line
			(start -0.7874 -0.4064)
			(end 0.7874 -0.4064)
			(stroke
				(width 0.1524)
				(type default)
			)
			(layer "F.SilkS")
		)
		(fp_line
			(start 0.7874 -0.4064)
			(end 0.7874 0.4064)
			(stroke
				(width 0.1524)
				(type default)
			)
			(layer "F.SilkS")
		)
		(fp_line
			(start -0.67945 0.3048)
			(end -0.67945 -0.305054)
			(stroke
				(width 0.1)
				(type default)
			)
			(layer "F.Fab")
		)
		(fp_line
			(start -0.12065 0.3048)
			(end -0.67945 0.3048)
			(stroke
				(width 0.1)
				(type default)
			)
			(layer "F.Fab")
		)
		(fp_line
			(start 0.120396 0.3048)
			(end 0.120396 0.2794)
			(stroke
				(width 0.1)
				(type default)
			)
			(layer "F.Fab")
		)
		(fp_line
			(start 0.67945 0.3048)
			(end 0.120396 0.3048)
			(stroke
				(width 0.1)
				(type default)
			)
			(layer "F.Fab")
		)
		(fp_line
			(start -0.12065 0.2794)
			(end -0.12065 0.3048)
			(stroke
				(width 0.1)
				(type default)
			)
			(layer "F.Fab")
		)
		(fp_line
			(start 0.120396 0.2794)
			(end -0.12065 0.2794)
			(stroke
				(width 0.1)
				(type default)
			)
			(layer "F.Fab")
		)
		(fp_line
			(start -0.12065 -0.2794)
			(end 0.12065 -0.2794)
			(stroke
				(width 0.1)
				(type default)
			)
			(layer "F.Fab")
		)
		(fp_line
			(start 0.12065 -0.2794)
			(end 0.12065 -0.3048)
			(stroke
				(width 0.1)
				(type default)
			)
			(layer "F.Fab")
		)
		(fp_line
			(start 0.12065 -0.3048)
			(end 0.67945 -0.3048)
			(stroke
				(width 0.1)
				(type default)
			)
			(layer "F.Fab")
		)
		(fp_line
			(start 0.67945 -0.3048)
			(end 0.67945 0.3048)
			(stroke
				(width 0.1)
				(type default)
			)
			(layer "F.Fab")
		)
		(fp_line
			(start -0.67945 -0.305054)
			(end -0.12065 -0.305054)
			(stroke
				(width 0.1)
				(type default)
			)
			(layer "F.Fab")
		)
		(fp_line
			(start -0.12065 -0.305054)
			(end -0.12065 -0.2794)
			(stroke
				(width 0.1)
				(type default)
			)
			(layer "F.Fab")
		)
		(pad "1" smd circle
			(at -0.40005 0 270)
			(size 0 0)
			(layers "F.Cu" "F.Mask" "F.Paste")
			(net "PVDD11_S3_P1")
		)
		(pad "2" smd circle
			(at 0.40005 0 270)
			(size 0 0)
			(layers "F.Cu" "F.Mask" "F.Paste")
			(net "GND")
		)
	)
	(footprint ""
		(layer "F.Cu")
		(at 178.71694 -397.388842 180)
		(property "Reference" "PC2193"
			(at 0 0 180)
			(layer "F.SilkS")
			(hide yes)
			(effects
				(font
					(size 1.27 1.27)
				)
			)
		)
		(property "Value" ""
			(at 0 0 180)
			(layer "F.Fab")
			(effects
				(font
					(size 1.27 1.27)
				)
			)
		)
		(duplicate_pad_numbers_are_jumpers no)
		(fp_line
			(start 0.7874 0.4064)
			(end -0.7874 0.4064)
			(stroke
				(width 0.1524)
				(type default)
			)
			(layer "F.SilkS")
		)
		(fp_line
			(start 0.7874 -0.4064)
			(end 0.7874 0.4064)
			(stroke
				(width 0.1524)
				(type default)
			)
			(layer "F.SilkS")
		)
		(fp_line
			(start -0.7874 0.4064)
			(end -0.7874 -0.4064)
			(stroke
				(width 0.1524)
				(type default)
			)
			(layer "F.SilkS")
		)
		(fp_line
			(start -0.7874 -0.4064)
			(end 0.7874 -0.4064)
			(stroke
				(width 0.1524)
				(type default)
			)
			(layer "F.SilkS")
		)
		(fp_line
			(start 0.67945 0.3048)
			(end 0.120396 0.3048)
			(stroke
				(width 0.1)
				(type default)
			)
			(layer "F.Fab")
		)
		(fp_line
			(start 0.67945 -0.3048)
			(end 0.67945 0.3048)
			(stroke
				(width 0.1)
				(type default)
			)
			(layer "F.Fab")
		)
		(fp_line
			(start 0.12065 -0.2794)
			(end 0.12065 -0.3048)
			(stroke
				(width 0.1)
				(type default)
			)
			(layer "F.Fab")
		)
		(fp_line
			(start 0.12065 -0.3048)
			(end 0.67945 -0.3048)
			(stroke
				(width 0.1)
				(type default)
			)
			(layer "F.Fab")
		)
		(fp_line
			(start 0.120396 0.3048)
			(end 0.120396 0.2794)
			(stroke
				(width 0.1)
				(type default)
			)
			(layer "F.Fab")
		)
		(fp_line
			(start 0.120396 0.2794)
			(end -0.12065 0.2794)
			(stroke
				(width 0.1)
				(type default)
			)
			(layer "F.Fab")
		)
		(fp_line
			(start -0.12065 0.3048)
			(end -0.67945 0.3048)
			(stroke
				(width 0.1)
				(type default)
			)
			(layer "F.Fab")
		)
		(fp_line
			(start -0.12065 0.2794)
			(end -0.12065 0.3048)
			(stroke
				(width 0.1)
				(type default)
			)
			(layer "F.Fab")
		)
		(fp_line
			(start -0.12065 -0.2794)
			(end 0.12065 -0.2794)
			(stroke
				(width 0.1)
				(type default)
			)
			(layer "F.Fab")
		)
		(fp_line
			(start -0.12065 -0.305054)
			(end -0.12065 -0.2794)
			(stroke
				(width 0.1)
				(type default)
			)
			(layer "F.Fab")
		)
		(fp_line
			(start -0.67945 0.3048)
			(end -0.67945 -0.305054)
			(stroke
				(width 0.1)
				(type default)
			)
			(layer "F.Fab")
		)
		(fp_line
			(start -0.67945 -0.305054)
			(end -0.12065 -0.305054)
			(stroke
				(width 0.1)
				(type default)
			)
			(layer "F.Fab")
		)
		(pad "1" smd circle
			(at -0.40005 0 180)
			(size 0 0)
			(layers "F.Cu" "F.Mask" "F.Paste")
			(net "HSC_IMON")
		)
		(pad "2" smd circle
			(at 0.40005 0 180)
			(size 0 0)
			(layers "F.Cu" "F.Mask" "F.Paste")
			(net "AGND_HSC")
		)
	)
	(footprint ""
		(layer "F.Cu")
		(at 286.571182 -13.373354)
		(property "Reference" "R4209"
			(at 0 0 0)
			(layer "F.SilkS")
			(hide yes)
			(effects
				(font
					(size 1.27 1.27)
				)
			)
		)
		(property "Value" ""
			(at 0 0 0)
			(layer "F.Fab")
			(effects
				(font
					(size 1.27 1.27)
				)
			)
		)
		(duplicate_pad_numbers_are_jumpers no)
		(fp_line
			(start -0.7874 -0.4064)
			(end 0.7874 -0.4064)
			(stroke
				(width 0.1524)
				(type default)
			)
			(layer "F.SilkS")
		)
		(fp_line
			(start -0.7874 0.4064)
			(end -0.7874 -0.4064)
			(stroke
				(width 0.1524)
				(type default)
			)
			(layer "F.SilkS")
		)
		(fp_line
			(start 0.7874 -0.4064)
			(end 0.7874 0.4064)
			(stroke
				(width 0.1524)
				(type default)
			)
			(layer "F.SilkS")
		)
		(fp_line
			(start 0.7874 0.4064)
			(end -0.7874 0.4064)
			(stroke
				(width 0.1524)
				(type default)
			)
			(layer "F.SilkS")
		)
		(fp_line
			(start -0.67945 -0.305054)
			(end -0.12065 -0.305054)
			(stroke
				(width 0.1)
				(type default)
			)
			(layer "F.Fab")
		)
		(fp_line
			(start -0.67945 0.3048)
			(end -0.67945 -0.305054)
			(stroke
				(width 0.1)
				(type default)
			)
			(layer "F.Fab")
		)
		(fp_line
			(start -0.12065 -0.305054)
			(end -0.12065 -0.2794)
			(stroke
				(width 0.1)
				(type default)
			)
			(layer "F.Fab")
		)
		(fp_line
			(start -0.12065 -0.2794)
			(end 0.12065 -0.2794)
			(stroke
				(width 0.1)
				(type default)
			)
			(layer "F.Fab")
		)
		(fp_line
			(start -0.12065 0.2794)
			(end -0.12065 0.3048)
			(stroke
				(width 0.1)
				(type default)
			)
			(layer "F.Fab")
		)
		(fp_line
			(start -0.12065 0.3048)
			(end -0.67945 0.3048)
			(stroke
				(width 0.1)
				(type default)
			)
			(layer "F.Fab")
		)
		(fp_line
			(start 0.120396 0.2794)
			(end -0.12065 0.2794)
			(stroke
				(width 0.1)
				(type default)
			)
			(layer "F.Fab")
		)
		(fp_line
			(start 0.120396 0.3048)
			(end 0.120396 0.2794)
			(stroke
				(width 0.1)
				(type default)
			)
			(layer "F.Fab")
		)
		(fp_line
			(start 0.12065 -0.3048)
			(end 0.67945 -0.3048)
			(stroke
				(width 0.1)
				(type default)
			)
			(layer "F.Fab")
		)
		(fp_line
			(start 0.12065 -0.2794)
			(end 0.12065 -0.3048)
			(stroke
				(width 0.1)
				(type default)
			)
			(layer "F.Fab")
		)
		(fp_line
			(start 0.67945 -0.3048)
			(end 0.67945 0.3048)
			(stroke
				(width 0.1)
				(type default)
			)
			(layer "F.Fab")
		)
		(fp_line
			(start 0.67945 0.3048)
			(end 0.120396 0.3048)
			(stroke
				(width 0.1)
				(type default)
			)
			(layer "F.Fab")
		)
		(pad "1" smd circle
			(at -0.40005 0)
			(size 0 0)
			(layers "F.Cu" "F.Mask" "F.Paste")
			(net "P3V3_AUX")
		)
		(pad "2" smd circle
			(at 0.40005 0)
			(size 0 0)
			(layers "F.Cu" "F.Mask" "F.Paste")
			(net "FM_THERMAL_ALERT_N")
		)
	)
)
